# BASEBOARD_FAB2 (Tioga Pass) — schematic netlist excerpt (pin names and nets, part order shuffled) for the footprints in the layout excerpt that follows; sources: Cadence DE-HDL packaged netlist, KiCad conversion of Wiwynn_Tioga_Pass_MB.brd

C3D4  CAP_A  22.0UF 4V 20% X6S  pkg 0603V  page 76 : A = PVCCMCP_CPU1 ; B = GND
R4D40  RES  4.75K 1% CHIP  pkg 0402  page 102 : A = P3V3_DB1200 ; B = FM_100M_N

(kicad_pcb
	(version 20260206)
	(generator "pcbnew")
	(generator_version "10.0")
	(general
		(thickness 1.6)
		(legacy_teardrops no)
	)
	(paper "A4")
	(title_block
		(title "Wiwynn_Tioga_Pass_MB.brd")
		(comment 1 "Tioga Pass / footprints 547-549 of 4770")
	)
	(layers
		(0 "F.Cu" signal "TOP")
		(4 "In1.Cu" signal "L2GND")
		(6 "In2.Cu" signal "L3")
		(8 "In3.Cu" signal "L4GND")
		(10 "In4.Cu" signal "L5")
		(12 "In5.Cu" signal "L6GND")
		(14 "In6.Cu" signal "L7VCC")
		(16 "In7.Cu" signal "L8VCC")
		(18 "In8.Cu" signal "L9GND")
		(20 "In9.Cu" signal "L10")
		(22 "In10.Cu" signal "L11GND")
		(24 "In11.Cu" signal "L12")
		(26 "In12.Cu" signal "L13GND")
		(2 "B.Cu" signal "BOTTOM")
		(9 "F.Adhes" user "F.Adhesive")
		(11 "B.Adhes" user "B.Adhesive")
		(13 "F.Paste" user "Package Geometry/Pastemask Top")
		(15 "B.Paste" user "Package Geometry/Pastemask Bottom")
		(5 "F.SilkS" user "Ref Des/Silkscreen Top")
		(7 "B.SilkS" user "Ref Des/Silkscreen Bottom")
		(1 "F.Mask" user "Board Geometry/Soldermask Top")
		(3 "B.Mask" user "Board Geometry/Soldermask Bottom")
		(17 "Dwgs.User" user "User.Drawings")
		(19 "Cmts.User" user "User.Comments")
		(21 "Eco1.User" user "User.Eco1")
		(23 "Eco2.User" user "User.Eco2")
		(25 "Edge.Cuts" user "Board Geometry/Outline")
		(27 "Margin" user)
		(31 "F.CrtYd" user "Package Geometry/Place Bound Top")
		(29 "B.CrtYd" user "Package Geometry/Place Bound Bottom")
		(35 "F.Fab" user "Ref Des/Assembly Top")
		(33 "B.Fab" user "Ref Des/Assembly Bottom")
	)
	(footprint ""
		(layer "F.Cu")
		(at 166.497 -73.66 180)
		(property "Reference" "R4D40"
			(at 0 0 180)
			(layer "F.SilkS")
			(hide yes)
			(effects
				(font
					(size 1.27 1.27)
				)
			)
		)
		(property "Value" ""
			(at 0 0 180)
			(layer "F.Fab")
			(effects
				(font
					(size 1.27 1.27)
				)
			)
		)
		(duplicate_pad_numbers_are_jumpers no)
		(fp_poly
			(pts
				(xy -0.2794 -0.1016) (xy 0.2794 -0.1016) (xy 0.2794 0.9906) (xy -0.2794 0.9906)
			)
			(stroke
				(width 0)
				(type default)
			)
			(fill no)
			(layer "F.CrtYd")
		)
		(fp_line
			(start 0.2794 0.9906)
			(end 0.2794 -0.1016)
			(stroke
				(width 0.1)
				(type default)
			)
			(layer "F.Fab")
		)
		(fp_line
			(start 0.2794 -0.1016)
			(end -0.2794 -0.1016)
			(stroke
				(width 0.1)
				(type default)
			)
			(layer "F.Fab")
		)
		(fp_line
			(start -0.2794 0.9906)
			(end 0.2794 0.9906)
			(stroke
				(width 0.1)
				(type default)
			)
			(layer "F.Fab")
		)
		(fp_line
			(start -0.2794 -0.1016)
			(end -0.2794 0.9906)
			(stroke
				(width 0.1)
				(type default)
			)
			(layer "F.Fab")
		)
		(pad "1" smd rect
			(at 0 0 180)
			(size 0.508 0.508)
			(layers "F.Cu" "F.Mask" "F.Paste")
			(net "P3V3_DB1200")
		)
		(pad "2" smd rect
			(at 0 0.889 180)
			(size 0.508 0.508)
			(layers "F.Cu" "F.Mask" "F.Paste")
			(net "FM_100M_N")
		)
		(zone
			(layer "F.Cu")
			(hatch none 0.5)
			(connect_pads
				(clearance 0)
			)
			(min_thickness 0.25)
			(keepout
				(tracks not_allowed)
				(vias allowed)
				(pads allowed)
				(copperpour not_allowed)
				(footprints allowed)
			)
			(placement
				(enabled no)
				(sheetname "")
			)
			(fill
				(thermal_gap 0.5)
				(thermal_bridge_width 0.5)
				(island_removal_mode 0)
			)
			(polygon
				(pts
					(xy 166.751 -74.295) (xy 166.243 -74.295) (xy 166.243 -73.914) (xy 166.751 -73.914)
				)
			)
		)
		(zone
			(layer "F.Cu")
			(hatch none 0.5)
			(connect_pads
				(clearance 0)
			)
			(min_thickness 0.25)
			(keepout
				(tracks allowed)
				(vias not_allowed)
				(pads allowed)
				(copperpour not_allowed)
				(footprints allowed)
			)
			(placement
				(enabled no)
				(sheetname "")
			)
			(fill
				(thermal_gap 0.5)
				(thermal_bridge_width 0.5)
				(island_removal_mode 0)
			)
			(polygon
				(pts
					(xy 166.751 -73.914) (xy 166.243 -73.914) (xy 166.243 -74.295) (xy 166.751 -74.295)
				)
			)
		)
	)
	(footprint ""
		(layer "F.Cu")
		(at 365.76 -130.302)
		(property "Reference" ""
			(at 0 0 0)
			(layer "F.SilkS")
			(hide yes)
			(effects
				(font
					(size 1.27 1.27)
				)
			)
		)
		(property "Value" ""
			(at 0 0 0)
			(layer "F.Fab")
			(effects
				(font
					(size 1.27 1.27)
				)
			)
		)
		(duplicate_pad_numbers_are_jumpers no)
		(fp_poly
			(pts
				(arc
					(start 2.032 0)
					(mid -2.032 0)
					(end 2.032 0)
				)
			)
			(stroke
				(width 0)
				(type default)
			)
			(fill no)
			(layer "F.CrtYd")
		)
		(pad "1" smd circle
			(at 0 0)
			(size 1.016 1.016)
			(layers "F.Cu" "F.Mask" "F.Paste")
			(net "Net_132")
		)
		(zone
			(layer "F.Cu")
			(hatch none 0.5)
			(connect_pads
				(clearance 0)
			)
			(min_thickness 0.25)
			(keepout
				(tracks not_allowed)
				(vias allowed)
				(pads allowed)
				(copperpour not_allowed)
				(footprints allowed)
			)
			(placement
				(enabled no)
				(sheetname "")
			)
			(fill
				(thermal_gap 0.5)
				(thermal_bridge_width 0.5)
				(island_removal_mode 0)
			)
			(polygon
				(pts
					(arc
						(start 367.284 -130.302)
						(mid 364.236 -130.302)
						(end 367.284 -130.302)
					)
				)
			)
		)
		(zone
			(layers "F.Cu" "B.Cu" "In1.Cu" "In2.Cu" "In3.Cu" "In4.Cu" "In5.Cu" "In6.Cu"
				"In7.Cu" "In8.Cu" "In9.Cu" "In10.Cu" "In11.Cu" "In12.Cu"
			)
			(hatch none 0.5)
			(connect_pads
				(clearance 0)
			)
			(min_thickness 0.25)
			(keepout
				(tracks allowed)
				(vias not_allowed)
				(pads allowed)
				(copperpour not_allowed)
				(footprints allowed)
			)
			(placement
				(enabled no)
				(sheetname "")
			)
			(fill
				(thermal_gap 0.5)
				(thermal_bridge_width 0.5)
				(island_removal_mode 0)
			)
			(polygon
				(pts
					(arc
						(start 367.284 -130.302)
						(mid 364.236 -130.302)
						(end 367.284 -130.302)
					)
				)
			)
		)
	)
	(footprint ""
		(layer "F.Cu")
		(at 108.252768 -79.6036 180)
		(property "Reference" "C3D4"
			(at 0 0 180)
			(layer "F.SilkS")
			(hide yes)
			(effects
				(font
					(size 1.27 1.27)
				)
			)
		)
		(property "Value" ""
			(at 0 0 180)
			(layer "F.Fab")
			(effects
				(font
					(size 1.27 1.27)
				)
			)
		)
		(duplicate_pad_numbers_are_jumpers no)
		(fp_poly
			(pts
				(xy -0.4953 -0.2032) (xy 0.4953 -0.2032) (xy 0.4953 1.6002) (xy -0.4953 1.6002)
			)
			(stroke
				(width 0)
				(type default)
			)
			(fill no)
			(layer "F.CrtYd")
		)
		(fp_line
			(start 0.4953 1.6002)
			(end -0.4953 1.6002)
			(stroke
				(width 0.1)
				(type default)
			)
			(layer "F.Fab")
		)
		(fp_line
			(start 0.4953 -0.2032)
			(end 0.4953 1.6002)
			(stroke
				(width 0.1)
				(type default)
			)
			(layer "F.Fab")
		)
		(fp_line
			(start -0.4953 1.6002)
			(end -0.4953 -0.2032)
			(stroke
				(width 0.1)
				(type default)
			)
			(layer "F.Fab")
		)
		(fp_line
			(start -0.4953 -0.2032)
			(end 0.4953 -0.2032)
			(stroke
				(width 0.1)
				(type default)
			)
			(layer "F.Fab")
		)
		(pad "1" smd rect
			(at 0 0 180)
			(size 0.762 0.889)
			(layers "F.Cu" "F.Mask" "F.Paste")
			(net "PVCCMCP_CPU1")
		)
		(pad "2" smd rect
			(at 0 1.397 180)
			(size 0.762 0.889)
			(layers "F.Cu" "F.Mask" "F.Paste")
			(net "GND")
		)
		(zone
			(layer "F.Cu")
			(hatch none 0.5)
			(connect_pads
				(clearance 0)
			)
			(min_thickness 0.25)
			(keepout
				(tracks not_allowed)
				(vias allowed)
				(pads allowed)
				(copperpour not_allowed)
				(footprints allowed)
			)
			(placement
				(enabled no)
				(sheetname "")
			)
			(fill
				(thermal_gap 0.5)
				(thermal_bridge_width 0.5)
				(island_removal_mode 0)
			)
			(polygon
				(pts
					(xy 108.633768 -80.0481) (xy 107.871768 -80.0481) (xy 107.871768 -80.5561) (xy 108.633768 -80.5561)
				)
			)
		)
	)
)
